(kicad_pcb
	(version 20260206)
	(generator "pcbnew")
	(generator_version "10.0")
	(general
		(thickness 1.6)
		(legacy_teardrops no)
	)
	(paper "A4")
	(title_block
		(title "04192023_DAF0TMB3IC0_F0TG_MB_C_brd_V02_OCP.brd")
		(comment 1 "Grand Teton / footprints 654-654 of 8354")
	)
	(layers
		(0 "F.Cu" signal "TOP")
		(4 "In1.Cu" signal "GND")
		(6 "In2.Cu" signal "IN1")
		(8 "In3.Cu" signal "GND1")
		(10 "In4.Cu" signal "IN2")
		(12 "In5.Cu" signal "GND2")
		(14 "In6.Cu" signal "IN3")
		(16 "In7.Cu" signal "GND3")
		(18 "In8.Cu" signal "VCC")
		(20 "In9.Cu" signal "VCC1")
		(22 "In10.Cu" signal "GND4")
		(24 "In11.Cu" signal "IN4")
		(26 "In12.Cu" signal "GND5")
		(28 "In13.Cu" signal "IN5")
		(30 "In14.Cu" signal "GND6")
		(32 "In15.Cu" signal "IN6")
		(34 "In16.Cu" signal "GND7")
		(2 "B.Cu" signal "BOTTOM")
		(9 "F.Adhes" user "F.Adhesive")
		(11 "B.Adhes" user "B.Adhesive")
		(13 "F.Paste" user "Package Geometry/Pastemask Top")
		(15 "B.Paste" user "Package Geometry/Pastemask Bottom")
		(5 "F.SilkS" user "Ref Des/Silkscreen Top")
		(7 "B.SilkS" user "Ref Des/Silkscreen Bottom")
		(1 "F.Mask" user "Board Geometry/Soldermask Top")
		(3 "B.Mask" user "Board Geometry/Soldermask Bottom")
		(17 "Dwgs.User" user "User.Drawings")
		(19 "Cmts.User" user "User.Comments")
		(21 "Eco1.User" user "User.Eco1")
		(23 "Eco2.User" user "User.Eco2")
		(25 "Edge.Cuts" user "Board Geometry/Outline")
		(27 "Margin" user)
		(31 "F.CrtYd" user "Package Geometry/Place Bound Top")
		(29 "B.CrtYd" user "Package Geometry/Place Bound Bottom")
		(35 "F.Fab" user "Ref Des/Assembly Top")
		(33 "B.Fab" user "Ref Des/Assembly Bottom")
	)
	(footprint ""
		(layer "F.Cu")
		(at 257.242056 -120.94337 180)
		(property "Reference" "R3713"
			(at 0 0 180)
			(layer "F.SilkS")
			(hide yes)
			(effects
				(font
					(size 1.27 1.27)
				)
			)
		)
		(property "Value" ""
			(at 0 0 180)
			(layer "F.Fab")
			(effects
				(font
					(size 1.27 1.27)
				)
			)
		)
		(duplicate_pad_numbers_are_jumpers no)
		(fp_line
			(start 0.7874 0.4064)
			(end -0.7874 0.4064)
			(stroke
				(width 0.1524)
				(type default)
			)
			(layer "F.SilkS")
		)
		(fp_line
			(start 0.7874 -0.4064)
			(end 0.7874 0.4064)
			(stroke
				(width 0.1524)
				(type default)
			)
			(layer "F.SilkS")
		)
		(fp_line
			(start -0.7874 0.4064)
			(end -0.7874 -0.4064)
			(stroke
				(width 0.1524)
				(type default)
			)
			(layer "F.SilkS")
		)
		(fp_line
			(start -0.7874 -0.4064)
			(end 0.7874 -0.4064)
			(stroke
				(width 0.1524)
				(type default)
			)
			(layer "F.SilkS")
		)
		(fp_line
			(start 0.67945 0.3048)
			(end 0.120396 0.3048)
			(stroke
				(width 0.1)
				(type default)
			)
			(layer "F.Fab")
		)
		(fp_line
			(start 0.67945 -0.3048)
			(end 0.67945 0.3048)
			(stroke
				(width 0.1)
				(type default)
			)
			(layer "F.Fab")
		)
		(fp_line
			(start 0.12065 -0.2794)
			(end 0.12065 -0.3048)
			(stroke
				(width 0.1)
				(type default)
			)
			(layer "F.Fab")
		)
		(fp_line
			(start 0.12065 -0.3048)
			(end 0.67945 -0.3048)
			(stroke
				(width 0.1)
				(type default)
			)
			(layer "F.Fab")
		)
		(fp_line
			(start 0.120396 0.3048)
			(end 0.120396 0.2794)
			(stroke
				(width 0.1)
				(type default)
			)
			(layer "F.Fab")
		)
		(fp_line
			(start 0.120396 0.2794)
			(end -0.12065 0.2794)
			(stroke
				(width 0.1)
				(type default)
			)
			(layer "F.Fab")
		)
		(fp_line
			(start -0.12065 0.3048)
			(end -0.67945 0.3048)
			(stroke
				(width 0.1)
				(type default)
			)
			(layer "F.Fab")
		)
		(fp_line
			(start -0.12065 0.2794)
			(end -0.12065 0.3048)
			(stroke
				(width 0.1)
				(type default)
			)
			(layer "F.Fab")
		)
		(fp_line
			(start -0.12065 -0.2794)
			(end 0.12065 -0.2794)
			(stroke
				(width 0.1)
				(type default)
			)
			(layer "F.Fab")
		)
		(fp_line
			(start -0.12065 -0.305054)
			(end -0.12065 -0.2794)
			(stroke
				(width 0.1)
				(type default)
			)
			(layer "F.Fab")
		)
		(fp_line
			(start -0.67945 0.3048)
			(end -0.67945 -0.305054)
			(stroke
				(width 0.1)
				(type default)
			)
			(layer "F.Fab")
		)
		(fp_line
			(start -0.67945 -0.305054)
			(end -0.12065 -0.305054)
			(stroke
				(width 0.1)
				(type default)
			)
			(layer "F.Fab")
		)
		(pad "1" smd circle
			(at -0.40005 0 180)
			(size 0 0)
			(layers "F.Cu" "F.Mask" "F.Paste")
			(net "SMB_VR_3V3AUX_SCL_R6")
		)
		(pad "2" smd circle
			(at 0.40005 0 180)
			(size 0 0)
			(layers "F.Cu" "F.Mask" "F.Paste")
			(net "SMB_VR_3V3AUX_SCL")
		)
	)
)
